(kicad_pcb
	(version 20260206)
	(generator "pcbnew")
	(generator_version "10.0")
	(general
		(thickness 1.6)
		(legacy_teardrops no)
	)
	(paper "A4")
	(title_block
		(title "Bryce Canyon_SCC_16316-1_OCP.brd")
		(comment 1 "Bryce Canyon / footprints 768-775 of 1561")
	)
	(layers
		(0 "F.Cu" signal "TOP")
		(4 "In1.Cu" signal "L2GND")
		(6 "In2.Cu" signal "L3")
		(8 "In3.Cu" signal "L4VCC")
		(10 "In4.Cu" signal "L5VCC")
		(12 "In5.Cu" signal "L6")
		(14 "In6.Cu" signal "L7GND")
		(2 "B.Cu" signal "BOTTOM")
		(9 "F.Adhes" user "F.Adhesive")
		(11 "B.Adhes" user "B.Adhesive")
		(13 "F.Paste" user "Package Geometry/Pastemask Top")
		(15 "B.Paste" user "Package Geometry/Pastemask Bottom")
		(5 "F.SilkS" user "Ref Des/Silkscreen Top")
		(7 "B.SilkS" user "Ref Des/Silkscreen Bottom")
		(1 "F.Mask" user "Board Geometry/Soldermask Top")
		(3 "B.Mask" user "Board Geometry/Soldermask Bottom")
		(17 "Dwgs.User" user "User.Drawings")
		(19 "Cmts.User" user "User.Comments")
		(21 "Eco1.User" user "User.Eco1")
		(23 "Eco2.User" user "User.Eco2")
		(25 "Edge.Cuts" user "Board Geometry/Outline")
		(27 "Margin" user)
		(31 "F.CrtYd" user "Package Geometry/Place Bound Top")
		(29 "B.CrtYd" user "Package Geometry/Place Bound Bottom")
		(35 "F.Fab" user "Ref Des/Assembly Top")
		(33 "B.Fab" user "Ref Des/Assembly Bottom")
	)
	(footprint ""
		(layer "B.Cu")
		(at 132.715 -89.916 180)
		(property "Reference" "R54"
			(at 0 0 0)
			(layer "B.SilkS")
			(hide yes)
			(effects
				(font
					(size 1.27 1.27)
				)
				(justify mirror)
			)
		)
		(property "Value" "4K7R2F-GP"
			(at -0.064008 -3.993896 180)
			(unlocked yes)
			(layer "B.Fab")
			(hide yes)
			(effects
				(font
					(size 1.016 1.016)
					(thickness 0.1524)
				)
				(justify mirror)
			)
		)
		(property "Device Type" "R402H16"
			(at -0.064008 -5.517896 180)
			(unlocked yes)
			(layer "B.Fab")
			(hide yes)
			(effects
				(font
					(size 1.016 1.016)
					(thickness 0.1524)
				)
				(justify mirror)
			)
		)
		(duplicate_pad_numbers_are_jumpers no)
		(fp_line
			(start 0.508 -0.9398)
			(end 0.508 0.9398)
			(stroke
				(width 0.1524)
				(type default)
			)
			(layer "B.SilkS")
		)
		(fp_line
			(start -0.508 -0.9398)
			(end 0.508 -0.9398)
			(stroke
				(width 0.1524)
				(type default)
			)
			(layer "B.SilkS")
		)
		(fp_rect
			(start 0.508 0.9398)
			(end -0.508 -0.9398)
			(stroke
				(width 0)
				(type default)
			)
			(fill no)
			(layer "B.CrtYd")
		)
		(fp_rect
			(start 0.508 0.9398)
			(end -0.508 -0.9398)
			(stroke
				(width 0)
				(type default)
			)
			(fill no)
			(layer "B.Fab")
		)
		(pad "1" smd custom
			(at 0 -0.4445)
			(size 0.1397 0.1397)
			(layers "B.Cu" "B.Mask" "B.Paste")
			(net "P1V8_E")
			(options
				(clearance outline)
				(anchor circle)
			)
			(primitives
				(gr_poly
					(pts
						(arc
							(start -0.1778 0.2794)
							(mid -0.249642 0.249642)
							(end -0.2794 0.1778)
						)
						(arc
							(start -0.2794 -0.1778)
							(mid -0.249642 -0.249642)
							(end -0.1778 -0.2794)
						)
						(arc
							(start 0.1778 -0.2794)
							(mid 0.249642 -0.249642)
							(end 0.2794 -0.1778)
						)
						(arc
							(start 0.2794 0.1778)
							(mid 0.249642 0.249642)
							(end 0.1778 0.2794)
						)
					)
					(width 0)
					(fill yes)
				)
			)
		)
		(pad "2" smd custom
			(at 0 0.4445)
			(size 0.1397 0.1397)
			(layers "B.Cu" "B.Mask" "B.Paste")
			(net "I2C_DPB_SCL3_LS")
			(options
				(clearance outline)
				(anchor circle)
			)
			(primitives
				(gr_poly
					(pts
						(arc
							(start -0.1778 0.2794)
							(mid -0.249642 0.249642)
							(end -0.2794 0.1778)
						)
						(arc
							(start -0.2794 -0.1778)
							(mid -0.249642 -0.249642)
							(end -0.1778 -0.2794)
						)
						(arc
							(start 0.1778 -0.2794)
							(mid 0.249642 -0.249642)
							(end 0.2794 -0.1778)
						)
						(arc
							(start 0.2794 0.1778)
							(mid 0.249642 0.249642)
							(end 0.1778 0.2794)
						)
					)
					(width 0)
					(fill yes)
				)
			)
		)
	)
	(footprint ""
		(layer "B.Cu")
		(at 177.805842 -41.329356 90)
		(property "Reference" "C436"
			(at 0 0 90)
			(layer "B.SilkS")
			(hide yes)
			(effects
				(font
					(size 1.27 1.27)
				)
				(justify mirror)
			)
		)
		(property "Value" "SCD1U6D3V1KX-GP"
			(at 2.8321 -1.7399 90)
			(unlocked yes)
			(layer "B.Fab")
			(hide yes)
			(effects
				(font
					(size 1.016 1.016)
					(thickness 0.1524)
				)
				(justify mirror)
			)
		)
		(property "Device Type" "C0201H13"
			(at 2.8321 -3.2639 90)
			(unlocked yes)
			(layer "B.Fab")
			(hide yes)
			(effects
				(font
					(size 1.016 1.016)
					(thickness 0.1524)
				)
				(justify mirror)
			)
		)
		(duplicate_pad_numbers_are_jumpers no)
		(fp_rect
			(start 0.2794 0.6477)
			(end -0.2794 -0.6477)
			(stroke
				(width 0)
				(type default)
			)
			(fill no)
			(layer "B.CrtYd")
		)
		(fp_rect
			(start 0.2794 0.6477)
			(end -0.2794 -0.6477)
			(stroke
				(width 0)
				(type default)
			)
			(fill no)
			(layer "B.Fab")
		)
		(pad "1" smd custom
			(at 0 -0.2794 270)
			(size 0.0762 0.0762)
			(layers "B.Cu" "B.Mask" "B.Paste")
			(net "P0V975")
			(options
				(clearance outline)
				(anchor circle)
			)
			(primitives
				(gr_poly
					(pts
						(arc
							(start 0.1524 0.127)
							(mid 0.137521 0.162921)
							(end 0.1016 0.1778)
						)
						(arc
							(start -0.1016 0.1778)
							(mid -0.137521 0.162921)
							(end -0.1524 0.127)
						)
						(arc
							(start -0.1524 -0.127)
							(mid -0.137521 -0.162921)
							(end -0.1016 -0.1778)
						)
						(arc
							(start 0.1016 -0.1778)
							(mid 0.137521 -0.162921)
							(end 0.1524 -0.127)
						)
					)
					(width 0)
					(fill yes)
				)
			)
		)
		(pad "2" smd custom
			(at 0 0.2794 270)
			(size 0.0762 0.0762)
			(layers "B.Cu" "B.Mask" "B.Paste")
			(net "GND")
			(options
				(clearance outline)
				(anchor circle)
			)
			(primitives
				(gr_poly
					(pts
						(arc
							(start 0.1524 0.127)
							(mid 0.137521 0.162921)
							(end 0.1016 0.1778)
						)
						(arc
							(start -0.1016 0.1778)
							(mid -0.137521 0.162921)
							(end -0.1524 0.127)
						)
						(arc
							(start -0.1524 -0.127)
							(mid -0.137521 -0.162921)
							(end -0.1016 -0.1778)
						)
						(arc
							(start 0.1016 -0.1778)
							(mid 0.137521 -0.162921)
							(end 0.1524 -0.127)
						)
					)
					(width 0)
					(fill yes)
				)
			)
		)
	)
	(footprint ""
		(layer "B.Cu")
		(at 183.668416 -84.718652 -90)
		(property "Reference" "R488"
			(at 0 0 90)
			(layer "B.SilkS")
			(hide yes)
			(effects
				(font
					(size 1.27 1.27)
				)
				(justify mirror)
			)
		)
		(property "Value" "10KR2F-2-GP"
			(at -0.064008 -3.993896 270)
			(unlocked yes)
			(layer "B.Fab")
			(hide yes)
			(effects
				(font
					(size 1.016 1.016)
					(thickness 0.1524)
				)
				(justify mirror)
			)
		)
		(property "Device Type" "R402H16"
			(at -0.064008 -5.517896 270)
			(unlocked yes)
			(layer "B.Fab")
			(hide yes)
			(effects
				(font
					(size 1.016 1.016)
					(thickness 0.1524)
				)
				(justify mirror)
			)
		)
		(duplicate_pad_numbers_are_jumpers no)
		(fp_line
			(start -0.508 -0.9398)
			(end 0.508 -0.9398)
			(stroke
				(width 0.1524)
				(type default)
			)
			(layer "B.SilkS")
		)
		(fp_line
			(start 0.508 -0.9398)
			(end 0.508 0.9398)
			(stroke
				(width 0.1524)
				(type default)
			)
			(layer "B.SilkS")
		)
		(fp_rect
			(start 0.508 0.9398)
			(end -0.508 -0.9398)
			(stroke
				(width 0)
				(type default)
			)
			(fill no)
			(layer "B.CrtYd")
		)
		(fp_rect
			(start 0.508 0.9398)
			(end -0.508 -0.9398)
			(stroke
				(width 0)
				(type default)
			)
			(fill no)
			(layer "B.Fab")
		)
		(pad "1" smd custom
			(at 0 -0.4445 90)
			(size 0.1397 0.1397)
			(layers "B.Cu" "B.Mask" "B.Paste")
			(net "GND")
			(options
				(clearance outline)
				(anchor circle)
			)
			(primitives
				(gr_poly
					(pts
						(arc
							(start -0.1778 0.2794)
							(mid -0.249642 0.249642)
							(end -0.2794 0.1778)
						)
						(arc
							(start -0.2794 -0.1778)
							(mid -0.249642 -0.249642)
							(end -0.1778 -0.2794)
						)
						(arc
							(start 0.1778 -0.2794)
							(mid 0.249642 -0.249642)
							(end 0.2794 -0.1778)
						)
						(arc
							(start 0.2794 0.1778)
							(mid 0.249642 0.249642)
							(end 0.1778 0.2794)
						)
					)
					(width 0)
					(fill yes)
				)
			)
		)
		(pad "2" smd custom
			(at 0 0.4445 90)
			(size 0.1397 0.1397)
			(layers "B.Cu" "B.Mask" "B.Paste")
			(net "P0V975")
			(options
				(clearance outline)
				(anchor circle)
			)
			(primitives
				(gr_poly
					(pts
						(arc
							(start -0.1778 0.2794)
							(mid -0.249642 0.249642)
							(end -0.2794 0.1778)
						)
						(arc
							(start -0.2794 -0.1778)
							(mid -0.249642 -0.249642)
							(end -0.1778 -0.2794)
						)
						(arc
							(start 0.1778 -0.2794)
							(mid 0.249642 -0.249642)
							(end 0.2794 -0.1778)
						)
						(arc
							(start 0.2794 0.1778)
							(mid 0.249642 0.249642)
							(end 0.1778 0.2794)
						)
					)
					(width 0)
					(fill yes)
				)
			)
		)
	)
	(footprint ""
		(layer "B.Cu")
		(at 176.200308 -37.03701 90)
		(property "Reference" "C428"
			(at 0 0 90)
			(layer "B.SilkS")
			(hide yes)
			(effects
				(font
					(size 1.27 1.27)
				)
				(justify mirror)
			)
		)
		(property "Value" "SCD1U6D3V1KX-GP"
			(at 2.8321 -1.7399 90)
			(unlocked yes)
			(layer "B.Fab")
			(hide yes)
			(effects
				(font
					(size 1.016 1.016)
					(thickness 0.1524)
				)
				(justify mirror)
			)
		)
		(property "Device Type" "C0201H13"
			(at 2.8321 -3.2639 90)
			(unlocked yes)
			(layer "B.Fab")
			(hide yes)
			(effects
				(font
					(size 1.016 1.016)
					(thickness 0.1524)
				)
				(justify mirror)
			)
		)
		(duplicate_pad_numbers_are_jumpers no)
		(fp_rect
			(start 0.2794 0.6477)
			(end -0.2794 -0.6477)
			(stroke
				(width 0)
				(type default)
			)
			(fill no)
			(layer "B.CrtYd")
		)
		(fp_rect
			(start 0.2794 0.6477)
			(end -0.2794 -0.6477)
			(stroke
				(width 0)
				(type default)
			)
			(fill no)
			(layer "B.Fab")
		)
		(pad "1" smd custom
			(at 0 -0.2794 270)
			(size 0.0762 0.0762)
			(layers "B.Cu" "B.Mask" "B.Paste")
			(net "P0V975")
			(options
				(clearance outline)
				(anchor circle)
			)
			(primitives
				(gr_poly
					(pts
						(arc
							(start 0.1524 0.127)
							(mid 0.137521 0.162921)
							(end 0.1016 0.1778)
						)
						(arc
							(start -0.1016 0.1778)
							(mid -0.137521 0.162921)
							(end -0.1524 0.127)
						)
						(arc
							(start -0.1524 -0.127)
							(mid -0.137521 -0.162921)
							(end -0.1016 -0.1778)
						)
						(arc
							(start 0.1016 -0.1778)
							(mid 0.137521 -0.162921)
							(end 0.1524 -0.127)
						)
					)
					(width 0)
					(fill yes)
				)
			)
		)
		(pad "2" smd custom
			(at 0 0.2794 270)
			(size 0.0762 0.0762)
			(layers "B.Cu" "B.Mask" "B.Paste")
			(net "GND")
			(options
				(clearance outline)
				(anchor circle)
			)
			(primitives
				(gr_poly
					(pts
						(arc
							(start 0.1524 0.127)
							(mid 0.137521 0.162921)
							(end 0.1016 0.1778)
						)
						(arc
							(start -0.1016 0.1778)
							(mid -0.137521 0.162921)
							(end -0.1524 0.127)
						)
						(arc
							(start -0.1524 -0.127)
							(mid -0.137521 -0.162921)
							(end -0.1016 -0.1778)
						)
						(arc
							(start 0.1016 -0.1778)
							(mid 0.137521 -0.162921)
							(end 0.1524 -0.127)
						)
					)
					(width 0)
					(fill yes)
				)
			)
		)
	)
	(footprint ""
		(layer "B.Cu")
		(at 112.395 -70.3834 180)
		(property "Reference" "C182"
			(at 0 0 0)
			(layer "B.SilkS")
			(hide yes)
			(effects
				(font
					(size 1.27 1.27)
				)
				(justify mirror)
			)
		)
		(property "Value" "SCD1U6D3V1KX-GP"
			(at 2.8321 -1.7399 180)
			(unlocked yes)
			(layer "B.Fab")
			(hide yes)
			(effects
				(font
					(size 1.016 1.016)
					(thickness 0.1524)
				)
				(justify mirror)
			)
		)
		(property "Device Type" "C0201H13"
			(at 2.8321 -3.2639 180)
			(unlocked yes)
			(layer "B.Fab")
			(hide yes)
			(effects
				(font
					(size 1.016 1.016)
					(thickness 0.1524)
				)
				(justify mirror)
			)
		)
		(duplicate_pad_numbers_are_jumpers no)
		(fp_rect
			(start 0.2794 0.6477)
			(end -0.2794 -0.6477)
			(stroke
				(width 0)
				(type default)
			)
			(fill no)
			(layer "B.CrtYd")
		)
		(fp_rect
			(start 0.2794 0.6477)
			(end -0.2794 -0.6477)
			(stroke
				(width 0)
				(type default)
			)
			(fill no)
			(layer "B.Fab")
		)
		(pad "1" smd custom
			(at 0 -0.2794)
			(size 0.0762 0.0762)
			(layers "B.Cu" "B.Mask" "B.Paste")
			(net "P0V9")
			(options
				(clearance outline)
				(anchor circle)
			)
			(primitives
				(gr_poly
					(pts
						(arc
							(start 0.1524 0.127)
							(mid 0.137521 0.162921)
							(end 0.1016 0.1778)
						)
						(arc
							(start -0.1016 0.1778)
							(mid -0.137521 0.162921)
							(end -0.1524 0.127)
						)
						(arc
							(start -0.1524 -0.127)
							(mid -0.137521 -0.162921)
							(end -0.1016 -0.1778)
						)
						(arc
							(start 0.1016 -0.1778)
							(mid 0.137521 -0.162921)
							(end 0.1524 -0.127)
						)
					)
					(width 0)
					(fill yes)
				)
			)
		)
		(pad "2" smd custom
			(at 0 0.2794)
			(size 0.0762 0.0762)
			(layers "B.Cu" "B.Mask" "B.Paste")
			(net "GND")
			(options
				(clearance outline)
				(anchor circle)
			)
			(primitives
				(gr_poly
					(pts
						(arc
							(start 0.1524 0.127)
							(mid 0.137521 0.162921)
							(end 0.1016 0.1778)
						)
						(arc
							(start -0.1016 0.1778)
							(mid -0.137521 0.162921)
							(end -0.1524 0.127)
						)
						(arc
							(start -0.1524 -0.127)
							(mid -0.137521 -0.162921)
							(end -0.1016 -0.1778)
						)
						(arc
							(start 0.1016 -0.1778)
							(mid 0.137521 -0.162921)
							(end 0.1524 -0.127)
						)
					)
					(width 0)
					(fill yes)
				)
			)
		)
	)
	(footprint ""
		(layer "B.Cu")
		(at 112.499902 -77.499972)
		(property "Reference" "TP47"
			(at 0 0 0)
			(layer "B.SilkS")
			(hide yes)
			(effects
				(font
					(size 1.27 1.27)
				)
				(justify mirror)
			)
		)
		(property "Value" "TPAD28-2-GP"
			(at 0.0127 -1.6637 0)
			(unlocked yes)
			(layer "B.Fab")
			(hide yes)
			(effects
				(font
					(size 1.016 1.016)
					(thickness 0.1524)
				)
				(justify mirror)
			)
		)
		(property "Device Type" "TPAD28"
			(at 0.0127 -3.1877 0)
			(unlocked yes)
			(layer "B.Fab")
			(hide yes)
			(effects
				(font
					(size 1.016 1.016)
					(thickness 0.1524)
				)
				(justify mirror)
			)
		)
		(duplicate_pad_numbers_are_jumpers no)
		(fp_poly
			(pts
				(arc
					(start 0.3556 0)
					(mid -0.3556 0)
					(end 0.3556 0)
				)
			)
			(stroke
				(width 0)
				(type default)
			)
			(fill no)
			(layer "B.CrtYd")
		)
		(fp_poly
			(pts
				(arc
					(start 0.6096 0)
					(mid -0.6096 0)
					(end 0.6096 0)
				)
			)
			(stroke
				(width 0)
				(type default)
			)
			(fill no)
			(layer "B.Fab")
		)
		(pad "1" smd circle
			(at 0 0 180)
			(size 0.7112 0.7112)
			(layers "B.Cu" "B.Mask" "B.Paste")
			(net "XM_GP_CS_3#_TP")
		)
	)
	(footprint ""
		(layer "B.Cu")
		(at 89.46642 -63.899034)
		(property "Reference" "L1"
			(at 0 0 0)
			(layer "B.SilkS")
			(hide yes)
			(effects
				(font
					(size 1.27 1.27)
				)
				(justify mirror)
			)
		)
		(property "Value" "MPZ2012S601AT-GP"
			(at 0 -4.2418 0)
			(unlocked yes)
			(layer "B.Fab")
			(hide yes)
			(effects
				(font
					(size 1.016 1.016)
					(thickness 0.1524)
				)
				(justify mirror)
			)
		)
		(property "Device Type" "L805H42"
			(at 0 -5.7912 0)
			(unlocked yes)
			(layer "B.Fab")
			(hide yes)
			(effects
				(font
					(size 1.016 1.016)
					(thickness 0.1524)
				)
				(justify mirror)
			)
		)
		(duplicate_pad_numbers_are_jumpers no)
		(fp_line
			(start -0.889 -1.7018)
			(end -0.889 1.7018)
			(stroke
				(width 0.1524)
				(type default)
			)
			(layer "B.SilkS")
		)
		(fp_line
			(start -0.889 1.7018)
			(end 0.889 1.7018)
			(stroke
				(width 0.1524)
				(type default)
			)
			(layer "B.SilkS")
		)
		(fp_line
			(start 0.889 -1.7018)
			(end -0.889 -1.7018)
			(stroke
				(width 0.1524)
				(type default)
			)
			(layer "B.SilkS")
		)
		(fp_line
			(start 0.889 1.7018)
			(end 0.889 -1.7018)
			(stroke
				(width 0.1524)
				(type default)
			)
			(layer "B.SilkS")
		)
		(fp_rect
			(start 0.9652 1.778)
			(end -0.9652 -1.778)
			(stroke
				(width 0)
				(type default)
			)
			(fill no)
			(layer "B.CrtYd")
		)
		(fp_rect
			(start 0.9652 1.778)
			(end -0.9652 -1.778)
			(stroke
				(width 0)
				(type default)
			)
			(fill no)
			(layer "B.Fab")
		)
		(pad "1" smd rect
			(at 0 -0.9652 180)
			(size 1.397 1.143)
			(layers "B.Cu" "B.Mask" "B.Paste")
			(net "XTAL_VDDA18")
		)
		(pad "2" smd rect
			(at 0 0.9652 180)
			(size 1.397 1.143)
			(layers "B.Cu" "B.Mask" "B.Paste")
			(net "P1V8_E")
		)
	)
	(footprint ""
		(layer "B.Cu")
		(at 108.585 -84.4296 180)
		(property "Reference" "R111"
			(at 0 0 0)
			(layer "B.SilkS")
			(hide yes)
			(effects
				(font
					(size 1.27 1.27)
				)
				(justify mirror)
			)
		)
		(property "Value" "4K75R2F-1-GP"
			(at -0.064008 -3.993896 180)
			(unlocked yes)
			(layer "B.Fab")
			(hide yes)
			(effects
				(font
					(size 1.016 1.016)
					(thickness 0.1524)
				)
				(justify mirror)
			)
		)
		(property "Device Type" "R402H16"
			(at -0.064008 -5.517896 180)
			(unlocked yes)
			(layer "B.Fab")
			(hide yes)
			(effects
				(font
					(size 1.016 1.016)
					(thickness 0.1524)
				)
				(justify mirror)
			)
		)
		(duplicate_pad_numbers_are_jumpers no)
		(fp_line
			(start 0.508 -0.9398)
			(end 0.508 0.9398)
			(stroke
				(width 0.1524)
				(type default)
			)
			(layer "B.SilkS")
		)
		(fp_line
			(start -0.508 -0.9398)
			(end 0.508 -0.9398)
			(stroke
				(width 0.1524)
				(type default)
			)
			(layer "B.SilkS")
		)
		(fp_rect
			(start 0.508 0.9398)
			(end -0.508 -0.9398)
			(stroke
				(width 0)
				(type default)
			)
			(fill no)
			(layer "B.CrtYd")
		)
		(fp_rect
			(start 0.508 0.9398)
			(end -0.508 -0.9398)
			(stroke
				(width 0)
				(type default)
			)
			(fill no)
			(layer "B.Fab")
		)
		(pad "1" smd custom
			(at 0 -0.4445)
			(size 0.1397 0.1397)
			(layers "B.Cu" "B.Mask" "B.Paste")
			(net "EXP_CPU_MODE_1")
			(options
				(clearance outline)
				(anchor circle)
			)
			(primitives
				(gr_poly
					(pts
						(arc
							(start -0.1778 0.2794)
							(mid -0.249642 0.249642)
							(end -0.2794 0.1778)
						)
						(arc
							(start -0.2794 -0.1778)
							(mid -0.249642 -0.249642)
							(end -0.1778 -0.2794)
						)
						(arc
							(start 0.1778 -0.2794)
							(mid 0.249642 -0.249642)
							(end 0.2794 -0.1778)
						)
						(arc
							(start 0.2794 0.1778)
							(mid 0.249642 0.249642)
							(end 0.1778 0.2794)
						)
					)
					(width 0)
					(fill yes)
				)
			)
		)
		(pad "2" smd custom
			(at 0 0.4445)
			(size 0.1397 0.1397)
			(layers "B.Cu" "B.Mask" "B.Paste")
			(net "GND")
			(options
				(clearance outline)
				(anchor circle)
			)
			(primitives
				(gr_poly
					(pts
						(arc
							(start -0.1778 0.2794)
							(mid -0.249642 0.249642)
							(end -0.2794 0.1778)
						)
						(arc
							(start -0.2794 -0.1778)
							(mid -0.249642 -0.249642)
							(end -0.1778 -0.2794)
						)
						(arc
							(start 0.1778 -0.2794)
							(mid 0.249642 -0.249642)
							(end 0.2794 -0.1778)
						)
						(arc
							(start 0.2794 0.1778)
							(mid 0.249642 0.249642)
							(end 0.1778 0.2794)
						)
					)
					(width 0)
					(fill yes)
				)
			)
		)
	)
)
